(kicad_pcb
	(version 20221018)
	(generator pcbnew)
	(general
    (thickness 1.562)
  )
	(paper "A4")
	(title_block
    (title "Thunderbolt PCIe Adaper")
    (date "2024-07-09")
    (rev "1.0.3")
    (comment 1 "www.antmicro.com")
    (comment 2 "Antmicro Ltd.")
		(comment 9 "footprints 254-262 of 271")
	)
	(layers
    (0 "F.Cu" signal)
    (1 "In1.Cu" signal)
    (2 "In2.Cu" signal)
    (3 "In3.Cu" signal)
    (4 "In4.Cu" signal)
    (31 "B.Cu" signal)
    (32 "B.Adhes" user "B.Adhesive")
    (33 "F.Adhes" user "F.Adhesive")
    (34 "B.Paste" user)
    (35 "F.Paste" user)
    (36 "B.SilkS" user "B.Silkscreen")
    (37 "F.SilkS" user "F.Silkscreen")
    (38 "B.Mask" user)
    (39 "F.Mask" user)
    (40 "Dwgs.User" user "User.Drawings")
    (41 "Cmts.User" user "User.Comments")
    (42 "Eco1.User" user "User.Eco1")
    (43 "Eco2.User" user "User.Eco2")
    (44 "Edge.Cuts" user)
    (45 "Margin" user)
    (46 "B.CrtYd" user "B.Courtyard")
    (47 "F.CrtYd" user "F.Courtyard")
    (48 "B.Fab" user)
    (49 "F.Fab" user)
  )
	(footprint "antmicro-footprints:R_0402_1005Metric" (layer "B.Cu")
    (at 140.34 61.03 -90)
    (descr "Resistor SMD 0402")
    (tags "resistor SMD 0402")
    (property "Author" "Antmicro")
    (property "License" "Apache-2.0")
    (property "MPN" "CR0402-FX-3301GLF")
    (property "Manufacturer" "Bourns")
    (property "Sheetfile" "tb.kicad_sch")
    (property "Sheetname" "TB Controller")
    (property "Tolerance" "1%")
    (property "Val" "3k3")
    (property "ki_description" "SMD Chip Resistor, 3.3 kohm, ± 1%, 63 mW, 0402 [1005 Metric], Thick Film, General Purpose")
    (property "ki_keywords" "0402, SMT, RESISTOR, PASSIVE")
    (attr smd)
    (fp_text reference "R53" (at -1.086 -1.392 90) (layer "B.SilkS")
        (effects (font (size 0.7 0.7) (thickness 0.15)) (justify left bottom mirror))
    )
    (fp_text value "R_3k3_0402" (at -1.011843 -1.772047 90) (layer "B.Fab")
        (effects (font (size 0.7 0.7) (thickness 0.15)) (justify left bottom mirror))
    )
    (fp_text user "${REFERENCE}" (at -0.95 -3.168 90) (layer "B.Fab") hide
        (effects (font (size 0.7 0.7) (thickness 0.15)) (justify left bottom mirror))
    )
    (fp_text user "Author: Antmicro" (at -0.95 -4.169 90) (layer "B.Fab") hide
        (effects (font (size 0.7 0.7) (thickness 0.15)) (justify left bottom mirror))
    )
    (fp_text user "License: Apache-2.0" (at -0.95 -5.169 90) (layer "B.Fab") hide
        (effects (font (size 0.7 0.7) (thickness 0.15)) (justify left bottom mirror))
    )
    (fp_rect (start -0.925 0.47) (end 0.925 -0.47)
      (stroke (width 0.05) (type default)) (fill none) (layer "B.CrtYd"))
    (fp_rect (start -0.5 0.25) (end 0.5 -0.25)
      (stroke (width 0.15) (type solid)) (fill none) (layer "B.Fab"))
    (pad "1" smd roundrect (at -0.48 0 270) (size 0.59 0.64) (layers "B.Cu" "B.Paste" "B.Mask") (roundrect_rratio 0.25)
      (net 2 "3V3_SYS") (pintype "passive"))
    (pad "2" smd roundrect (at 0.48 0 270) (size 0.59 0.64) (layers "B.Cu" "B.Paste" "B.Mask") (roundrect_rratio 0.25)
      (net 89 "/TB Controller/FLASH_HOLD") (pintype "passive"))
  )
	(footprint "antmicro-footprints:R_0402_1005Metric" (layer "B.Cu")
    (at 111.715 83.68)
    (descr "Resistor SMD 0402")
    (tags "resistor SMD 0402")
    (property "Author" "Antmicro")
    (property "License" "Apache-2.0")
    (property "MPN" "CR0402-FX-1003GLF")
    (property "Manufacturer" "Bourns")
    (property "Sheetfile" "power.kicad_sch")
    (property "Sheetname" "Power")
    (property "Tolerance" "1%")
    (property "Val" "100k")
    (property "dnp" "")
    (property "ki_description" "SMD Chip Resistor, 100 kohm, ± 1%, 62.5 mW, 0402 [1005 Metric], Thick Film, General Purpose")
    (property "ki_keywords" "0402, SMT, RESISTOR, PASSIVE")
    (attr smd)
    (fp_text reference "R24" (at 1.061 -4.686 180) (layer "B.SilkS")
        (effects (font (size 0.7 0.7) (thickness 0.15)) (justify left bottom mirror))
    )
    (fp_text value "R_100k_0402" (at -1.011843 -1.772047 180) (layer "B.Fab")
        (effects (font (size 0.7 0.7) (thickness 0.15)) (justify left bottom mirror))
    )
    (fp_text user "Author: Antmicro" (at -0.95 -4.169 180) (layer "B.Fab") hide
        (effects (font (size 0.7 0.7) (thickness 0.15)) (justify left bottom mirror))
    )
    (fp_text user "${REFERENCE}" (at -0.95 -3.168 180) (layer "B.Fab") hide
        (effects (font (size 0.7 0.7) (thickness 0.15)) (justify left bottom mirror))
    )
    (fp_text user "License: Apache-2.0" (at -0.95 -5.169 180) (layer "B.Fab") hide
        (effects (font (size 0.7 0.7) (thickness 0.15)) (justify left bottom mirror))
    )
    (fp_rect (start -0.925 0.47) (end 0.925 -0.47)
      (stroke (width 0.05) (type default)) (fill none) (layer "B.CrtYd"))
    (fp_rect (start -0.5 0.25) (end 0.5 -0.25)
      (stroke (width 0.15) (type solid)) (fill none) (layer "B.Fab"))
    (pad "1" smd roundrect (at -0.48 0) (size 0.59 0.64) (layers "B.Cu" "B.Paste" "B.Mask") (roundrect_rratio 0.25)
      (net 1 "GND") (pintype "passive"))
    (pad "2" smd roundrect (at 0.48 0) (size 0.59 0.64) (layers "B.Cu" "B.Paste" "B.Mask") (roundrect_rratio 0.25)
      (net 159 "Net-(U1-SYNC{slash}MODE)") (pintype "passive"))
  )
	(footprint "antmicro-footprints:C_0402_1005Metric" (layer "B.Cu")
    (at 154.91 59.47 90)
    (descr "Capacitor SMD 0402")
    (tags "capacitor SMD 0402")
    (property "Author" "Antmicro")
    (property "Dielectric" "")
    (property "License" "Apache-2.0")
    (property "MPN" "C1005X5R1A225K050BC")
    (property "Manufacturer" "TDK")
    (property "Sheetfile" "power.kicad_sch")
    (property "Sheetname" "Power")
    (property "Val" "2u2")
    (property "Voltage" "")
    (property "ki_description" "SMD Multilayer Ceramic Capacitor, 2.2 µF, 10 V, 0402 [1005 Metric], ± 10%, X5R, C")
    (property "ki_keywords" "0402, SMT, CAPACITOR, PASSIVE, CERAMIC, MLCC")
    (attr smd)
    (fp_text reference "C36" (at 4.86 -5.558 270) (layer "B.SilkS")
        (effects (font (size 0.7 0.7) (thickness 0.15)) (justify left bottom mirror))
    )
    (fp_text value "C_2u2_0402" (at -1.022927 -2.155213 270) (layer "B.Fab")
        (effects (font (size 0.7 0.7) (thickness 0.15)) (justify left bottom mirror))
    )
    (fp_text user "Author: Antmicro" (at -0.939 -3.399 270) (layer "B.Fab") hide
        (effects (font (size 0.7 0.7) (thickness 0.15)) (justify left bottom mirror))
    )
    (fp_text user "${REFERENCE}" (at -0.939 -4.599 270) (layer "B.Fab") hide
        (effects (font (size 0.7 0.7) (thickness 0.15)) (justify left bottom mirror))
    )
    (fp_text user "License: Apache-2.0" (at -0.939 -5.799 270) (layer "B.Fab") hide
        (effects (font (size 0.7 0.7) (thickness 0.15)) (justify left bottom mirror))
    )
    (fp_rect (start -0.925 0.47) (end 0.925 -0.47)
      (stroke (width 0.05) (type default)) (fill none) (layer "B.CrtYd"))
    (fp_line (start -0.494 -0.248) (end -0.494 0.25)
      (stroke (width 0.15) (type solid)) (layer "B.Fab"))
    (fp_line (start -0.494 0.25) (end 0.504 0.25)
      (stroke (width 0.15) (type solid)) (layer "B.Fab"))
    (fp_line (start 0.504 -0.248) (end -0.494 -0.248)
      (stroke (width 0.15) (type solid)) (layer "B.Fab"))
    (fp_line (start 0.504 0.25) (end 0.504 -0.248)
      (stroke (width 0.15) (type solid)) (layer "B.Fab"))
    (pad "1" smd roundrect (at -0.48 0 90) (size 0.59 0.64) (layers "B.Cu" "B.Paste" "B.Mask") (roundrect_rratio 0.25)
      (net 103 "Net-(U3-LDO_1V8D)") (pintype "passive"))
    (pad "2" smd roundrect (at 0.48 0 90) (size 0.59 0.64) (layers "B.Cu" "B.Paste" "B.Mask") (roundrect_rratio 0.25)
      (net 1 "GND") (pintype "passive"))
  )
	(footprint "antmicro-footprints:C_0402_1005Metric" (layer "B.Cu")
    (at 141.15 74.482 -90)
    (descr "Capacitor SMD 0402")
    (tags "capacitor SMD 0402")
    (property "Author" "Antmicro")
    (property "Dielectric" "X5R")
    (property "License" "Apache-2.0")
    (property "MPN" "GRM155R61H104KE14D")
    (property "Manufacturer" "Murata")
    (property "Sheetfile" "tb-power.kicad_sch")
    (property "Sheetname" "Thunderbolt Controller - Power")
    (property "Val" "100n")
    (property "Voltage" "50V")
    (property "ki_description" "SMD Multilayer Ceramic Capacitor, 0.1 µF, 50 V, 0402 [1005 Metric], ± 10%, X5R, GRM Series")
    (property "ki_keywords" "0402, SMT, CAPACITOR, PASSIVE, CERAMIC, MLCC")
    (attr smd)
    (fp_text reference "C91" (at -5.521 -1.471 90) (layer "B.SilkS")
        (effects (font (size 0.7 0.7) (thickness 0.15)) (justify left bottom mirror))
    )
    (fp_text value "C_100n_0402" (at -1.022927 -2.155213 90) (layer "B.Fab")
        (effects (font (size 0.7 0.7) (thickness 0.15)) (justify left bottom mirror))
    )
    (fp_text user "${REFERENCE}" (at -0.939 -4.599 90) (layer "B.Fab") hide
        (effects (font (size 0.7 0.7) (thickness 0.15)) (justify left bottom mirror))
    )
    (fp_text user "License: Apache-2.0" (at -0.939 -5.799 90) (layer "B.Fab") hide
        (effects (font (size 0.7 0.7) (thickness 0.15)) (justify left bottom mirror))
    )
    (fp_text user "Author: Antmicro" (at -0.939 -3.399 90) (layer "B.Fab") hide
        (effects (font (size 0.7 0.7) (thickness 0.15)) (justify left bottom mirror))
    )
    (fp_rect (start -0.925 0.47) (end 0.925 -0.47)
      (stroke (width 0.05) (type default)) (fill none) (layer "B.CrtYd"))
    (fp_line (start -0.494 -0.248) (end -0.494 0.25)
      (stroke (width 0.15) (type solid)) (layer "B.Fab"))
    (fp_line (start -0.494 0.25) (end 0.504 0.25)
      (stroke (width 0.15) (type solid)) (layer "B.Fab"))
    (fp_line (start 0.504 -0.248) (end -0.494 -0.248)
      (stroke (width 0.15) (type solid)) (layer "B.Fab"))
    (fp_line (start 0.504 0.25) (end 0.504 -0.248)
      (stroke (width 0.15) (type solid)) (layer "B.Fab"))
    (pad "1" smd roundrect (at -0.48 0 270) (size 0.59 0.64) (layers "B.Cu" "B.Paste" "B.Mask") (roundrect_rratio 0.25)
      (net 1 "GND") (pintype "passive"))
    (pad "2" smd roundrect (at 0.48 0 270) (size 0.59 0.64) (layers "B.Cu" "B.Paste" "B.Mask") (roundrect_rratio 0.25)
      (net 2 "3V3_SYS") (pintype "passive"))
  )
	(footprint "antmicro-footprints:R_0402_1005Metric" (layer "B.Cu")
    (at 132.1 68.77 90)
    (descr "Resistor SMD 0402")
    (tags "resistor SMD 0402")
    (property "Author" "Antmicro")
    (property "License" "Apache-2.0")
    (property "MPN" "CR0402-FX-1002GLF")
    (property "Manufacturer" "Bourns")
    (property "Sheetfile" "tb.kicad_sch")
    (property "Sheetname" "TB Controller")
    (property "Tolerance" "1%")
    (property "Val" "10k")
    (property "ki_description" "SMD Chip Resistor, 10 kohm, ± 1%, 62.5 mW, 0402 [1005 Metric], Thick Film, General Purpose")
    (property "ki_keywords" "0402, SMT, RESISTOR, PASSIVE")
    (attr smd)
    (fp_text reference "R78" (at 1.079 -2.678 270) (layer "B.SilkS")
        (effects (font (size 0.7 0.7) (thickness 0.15)) (justify left bottom mirror))
    )
    (fp_text value "R_10k_0402" (at -1.011843 -1.772047 270) (layer "B.Fab")
        (effects (font (size 0.7 0.7) (thickness 0.15)) (justify left bottom mirror))
    )
    (fp_text user "License: Apache-2.0" (at -0.95 -5.169 270) (layer "B.Fab") hide
        (effects (font (size 0.7 0.7) (thickness 0.15)) (justify left bottom mirror))
    )
    (fp_text user "${REFERENCE}" (at -0.95 -3.168 270) (layer "B.Fab") hide
        (effects (font (size 0.7 0.7) (thickness 0.15)) (justify left bottom mirror))
    )
    (fp_text user "Author: Antmicro" (at -0.95 -4.169 270) (layer "B.Fab") hide
        (effects (font (size 0.7 0.7) (thickness 0.15)) (justify left bottom mirror))
    )
    (fp_rect (start -0.925 0.47) (end 0.925 -0.47)
      (stroke (width 0.05) (type default)) (fill none) (layer "B.CrtYd"))
    (fp_rect (start -0.5 0.25) (end 0.5 -0.25)
      (stroke (width 0.15) (type solid)) (fill none) (layer "B.Fab"))
    (pad "1" smd roundrect (at -0.48 0 90) (size 0.59 0.64) (layers "B.Cu" "B.Paste" "B.Mask") (roundrect_rratio 0.25)
      (net 193 "Net-(U4C-GPIO_4)") (pintype "passive"))
    (pad "2" smd roundrect (at 0.48 0 90) (size 0.59 0.64) (layers "B.Cu" "B.Paste" "B.Mask") (roundrect_rratio 0.25)
      (net 1 "GND") (pintype "passive"))
  )
	(footprint "antmicro-footprints:Fiducial_1mm_Mask3mm" (layer "B.Cu")
    (at 102 91 180)
    (descr "Circular Fiducial, 1.5mm bare copper, 3mm soldermask opening")
    (tags "fiducial")
    (property "Author" "Antmicro")
    (property "License" "Apache-2.0")
    (property "Sheetfile" "thunderbolt-pcie-adapter.kicad_sch")
    (property "Sheetname" "")
    (property "exclude_from_bom" "")
    (property "ki_description" "Fiducial mask")
    (attr through_hole exclude_from_bom)
    (fp_text reference "FID5" (at -0.616 -2.599) (layer "B.SilkS")
        (effects (font (size 0.7 0.7) (thickness 0.15)) (justify left bottom mirror))
    )
    (fp_text value "Fiducial_1mm_Mask3mm" (at 0 -2.603) (layer "B.Fab")
        (effects (font (size 0.7 0.7) (thickness 0.15)) (justify left bottom mirror))
    )
    (fp_text user "License: Apache-2.0" (at -1.25 -7.003) (layer "B.Fab") hide
        (effects (font (size 0.7 0.7) (thickness 0.15)) (justify left bottom mirror))
    )
    (fp_text user "Author: Antmicro" (at -1.25 -5.803) (layer "B.Fab") hide
        (effects (font (size 0.7 0.7) (thickness 0.15)) (justify left bottom mirror))
    )
    (fp_text user "${REFERENCE}" (at -1.25 -4.603) (layer "B.Fab") hide
        (effects (font (size 0.7 0.7) (thickness 0.15)) (justify left bottom mirror))
    )
    (fp_circle (center 0 0) (end 1.5 0)
      (stroke (width 0.05) (type solid)) (fill none) (layer "B.CrtYd"))
    (fp_circle (center 0 0) (end 1.5 0)
      (stroke (width 0.15) (type solid)) (fill none) (layer "B.Fab"))
    (pad "" smd circle (at 0 0 180) (size 1 1) (layers "B.Cu" "B.Mask")
      (solder_mask_margin 1) (clearance 1))
  )
	(footprint "antmicro-footprints:C_0402_1005Metric" (layer "B.Cu")
    (at 130.9 77.9)
    (descr "Capacitor SMD 0402")
    (tags "capacitor SMD 0402")
    (property "Author" "Antmicro")
    (property "Dielectric" "")
    (property "License" "Apache-2.0")
    (property "MPN" "C1005X6S1A105K050BC")
    (property "Manufacturer" "TDK")
    (property "Sheetfile" "tb-power.kicad_sch")
    (property "Sheetname" "Thunderbolt Controller - Power")
    (property "Val" "1u")
    (property "Voltage" "")
    (property "ki_description" "SMD Multilayer Ceramic Capacitor, 1 µF, 10 V, 0402 [1005 Metric], ± 10%, X6S, C")
    (property "ki_keywords" "0402, SMT, CAPACITOR, PASSIVE, CERAMIC, MLCC")
    (attr smd)
    (fp_text reference "C60" (at 17.309 7.571 180) (layer "B.SilkS")
        (effects (font (size 0.7 0.7) (thickness 0.15)) (justify left bottom mirror))
    )
    (fp_text value "C_1u_0402" (at -1.022927 -2.155213 180) (layer "B.Fab")
        (effects (font (size 0.7 0.7) (thickness 0.15)) (justify left bottom mirror))
    )
    (fp_text user "${REFERENCE}" (at -0.939 -4.599 180) (layer "B.Fab") hide
        (effects (font (size 0.7 0.7) (thickness 0.15)) (justify left bottom mirror))
    )
    (fp_text user "License: Apache-2.0" (at -0.939 -5.799 180) (layer "B.Fab") hide
        (effects (font (size 0.7 0.7) (thickness 0.15)) (justify left bottom mirror))
    )
    (fp_text user "Author: Antmicro" (at -0.939 -3.399 180) (layer "B.Fab") hide
        (effects (font (size 0.7 0.7) (thickness 0.15)) (justify left bottom mirror))
    )
    (fp_rect (start -0.925 0.47) (end 0.925 -0.47)
      (stroke (width 0.05) (type default)) (fill none) (layer "B.CrtYd"))
    (fp_line (start -0.494 -0.248) (end -0.494 0.25)
      (stroke (width 0.15) (type solid)) (layer "B.Fab"))
    (fp_line (start -0.494 0.25) (end 0.504 0.25)
      (stroke (width 0.15) (type solid)) (layer "B.Fab"))
    (fp_line (start 0.504 -0.248) (end -0.494 -0.248)
      (stroke (width 0.15) (type solid)) (layer "B.Fab"))
    (fp_line (start 0.504 0.25) (end 0.504 -0.248)
      (stroke (width 0.15) (type solid)) (layer "B.Fab"))
    (pad "1" smd roundrect (at -0.48 0) (size 0.59 0.64) (layers "B.Cu" "B.Paste" "B.Mask") (roundrect_rratio 0.25)
      (net 1 "GND") (pintype "passive"))
    (pad "2" smd roundrect (at 0.48 0) (size 0.59 0.64) (layers "B.Cu" "B.Paste" "B.Mask") (roundrect_rratio 0.25)
      (net 107 "Net-(C54-Pad2)") (pintype "passive"))
  )
	(footprint "antmicro-footprints:C_0402_1005Metric" (layer "B.Cu")
    (at 165.2 77.912922 90)
    (descr "Capacitor SMD 0402")
    (tags "capacitor SMD 0402")
    (property "Author" "Antmicro")
    (property "Dielectric" "X5R")
    (property "License" "Apache-2.0")
    (property "MPN" "GRM155R61H104KE14D")
    (property "Manufacturer" "Murata")
    (property "Sheetfile" "connectors.kicad_sch")
    (property "Sheetname" "Connectors")
    (property "Val" "100n")
    (property "Voltage" "50V")
    (property "ki_description" "SMD Multilayer Ceramic Capacitor, 0.1 µF, 50 V, 0402 [1005 Metric], ± 10%, X5R, GRM Series")
    (property "ki_keywords" "0402, SMT, CAPACITOR, PASSIVE, CERAMIC, MLCC")
    (attr smd)
    (fp_text reference "C5" (at 0.696922 -0.608 270) (layer "B.SilkS")
        (effects (font (size 0.7 0.7) (thickness 0.15)) (justify left bottom mirror))
    )
    (fp_text value "C_100n_0402" (at -1.022927 -2.155213 270) (layer "B.Fab")
        (effects (font (size 0.7 0.7) (thickness 0.15)) (justify left bottom mirror))
    )
    (fp_text user "License: Apache-2.0" (at -0.939 -5.799 270) (layer "B.Fab") hide
        (effects (font (size 0.7 0.7) (thickness 0.15)) (justify left bottom mirror))
    )
    (fp_text user "Author: Antmicro" (at -0.939 -3.399 270) (layer "B.Fab") hide
        (effects (font (size 0.7 0.7) (thickness 0.15)) (justify left bottom mirror))
    )
    (fp_text user "${REFERENCE}" (at -0.939 -4.599 270) (layer "B.Fab") hide
        (effects (font (size 0.7 0.7) (thickness 0.15)) (justify left bottom mirror))
    )
    (fp_rect (start -0.925 0.47) (end 0.925 -0.47)
      (stroke (width 0.05) (type default)) (fill none) (layer "B.CrtYd"))
    (fp_line (start -0.494 -0.248) (end -0.494 0.25)
      (stroke (width 0.15) (type solid)) (layer "B.Fab"))
    (fp_line (start -0.494 0.25) (end 0.504 0.25)
      (stroke (width 0.15) (type solid)) (layer "B.Fab"))
    (fp_line (start 0.504 -0.248) (end -0.494 -0.248)
      (stroke (width 0.15) (type solid)) (layer "B.Fab"))
    (fp_line (start 0.504 0.25) (end 0.504 -0.248)
      (stroke (width 0.15) (type solid)) (layer "B.Fab"))
    (pad "1" smd roundrect (at -0.48 0 90) (size 0.59 0.64) (layers "B.Cu" "B.Paste" "B.Mask") (roundrect_rratio 0.25)
      (net 1 "GND") (pintype "passive"))
    (pad "2" smd roundrect (at 0.48 0 90) (size 0.59 0.64) (layers "B.Cu" "B.Paste" "B.Mask") (roundrect_rratio 0.25)
      (net 3 "5V0_USB") (pintype "passive"))
  )
	(footprint "antmicro-footprints:R_0402_1005Metric" (layer "B.Cu")
    (at 111.095 86.169999 90)
    (descr "Resistor SMD 0402")
    (tags "resistor SMD 0402")
    (property "Author" "Antmicro")
    (property "License" "Apache-2.0")
    (property "MPN" "CR0402-FX-1202GLF")
    (property "Manufacturer" "Bourns")
    (property "Sheetfile" "power.kicad_sch")
    (property "Sheetname" "Power")
    (property "Tolerance" "1%")
    (property "Val" "12k")
    (property "ki_description" "SMD Chip Resistor, 12 kohm, ± 1%, 62.5 mW, 0402 [1005 Metric], Thick Film, General Purpose")
    (property "ki_keywords" "0402, SMT, RESISTOR, PASSIVE")
    (attr smd)
    (fp_text reference "R25" (at -2.984001 0.411 90) (layer "B.SilkS")
        (effects (font (size 0.7 0.7) (thickness 0.15)) (justify right bottom mirror))
    )
    (fp_text value "R_12k_0402" (at -1.011843 -1.772047 90) (layer "B.Fab")
        (effects (font (size 0.7 0.7) (thickness 0.15)) (justify right bottom mirror))
    )
    (fp_text user "License: Apache-2.0" (at -0.95 -5.169 90) (layer "B.Fab") hide
        (effects (font (size 0.7 0.7) (thickness 0.15)) (justify right bottom mirror))
    )
    (fp_text user "Author: Antmicro" (at -0.95 -4.169 90) (layer "B.Fab") hide
        (effects (font (size 0.7 0.7) (thickness 0.15)) (justify right bottom mirror))
    )
    (fp_text user "${REFERENCE}" (at -0.95 -3.168 90) (layer "B.Fab") hide
        (effects (font (size 0.7 0.7) (thickness 0.15)) (justify right bottom mirror))
    )
    (fp_rect (start -0.925 0.47) (end 0.925 -0.47)
      (stroke (width 0.05) (type default)) (fill none) (layer "B.CrtYd"))
    (fp_rect (start -0.5 0.25) (end 0.5 -0.25)
      (stroke (width 0.15) (type solid)) (fill none) (layer "B.Fab"))
    (pad "1" smd roundrect (at -0.48 0 90) (size 0.59 0.64) (layers "B.Cu" "B.Paste" "B.Mask") (roundrect_rratio 0.25)
      (net 7 "Net-(C30-Pad2)") (pintype "passive"))
    (pad "2" smd roundrect (at 0.48 0 90) (size 0.59 0.64) (layers "B.Cu" "B.Paste" "B.Mask") (roundrect_rratio 0.25)
      (net 160 "Net-(U1-VC)") (pintype "passive"))
  )
)
